(kicad_pcb
	(version 20260206)
	(generator "pcbnew")
	(generator_version "10.0")
	(general
		(thickness 1.6)
		(legacy_teardrops no)
	)
	(paper "A4")
	(title_block
		(title "03242023_DA0F0TMBIJ0_F0T_Motherboard_J_brd_V01_OCP.brd")
		(comment 1 "Grand Teton / footprints 3275-3280 of 6105")
	)
	(layers
		(0 "F.Cu" signal "TOP")
		(4 "In1.Cu" signal "GND")
		(6 "In2.Cu" signal "IN1")
		(8 "In3.Cu" signal "GND1")
		(10 "In4.Cu" signal "IN2")
		(12 "In5.Cu" signal "GND2")
		(14 "In6.Cu" signal "IN3")
		(16 "In7.Cu" signal "GND3")
		(18 "In8.Cu" signal "VCC")
		(20 "In9.Cu" signal "VCC1")
		(22 "In10.Cu" signal "GND4")
		(24 "In11.Cu" signal "IN4")
		(26 "In12.Cu" signal "GND5")
		(28 "In13.Cu" signal "IN5")
		(30 "In14.Cu" signal "GND6")
		(32 "In15.Cu" signal "IN6")
		(34 "In16.Cu" signal "GND7")
		(2 "B.Cu" signal "BOTTOM")
		(9 "F.Adhes" user "F.Adhesive")
		(11 "B.Adhes" user "B.Adhesive")
		(13 "F.Paste" user "Package Geometry/Pastemask Top")
		(15 "B.Paste" user "Package Geometry/Pastemask Bottom")
		(5 "F.SilkS" user "Ref Des/Silkscreen Top")
		(7 "B.SilkS" user "Ref Des/Silkscreen Bottom")
		(1 "F.Mask" user "Board Geometry/Soldermask Top")
		(3 "B.Mask" user "Board Geometry/Soldermask Bottom")
		(17 "Dwgs.User" user "User.Drawings")
		(19 "Cmts.User" user "User.Comments")
		(21 "Eco1.User" user "User.Eco1")
		(23 "Eco2.User" user "User.Eco2")
		(25 "Edge.Cuts" user "Board Geometry/Outline")
		(27 "Margin" user)
		(31 "F.CrtYd" user "Package Geometry/Place Bound Top")
		(29 "B.CrtYd" user "Package Geometry/Place Bound Bottom")
		(35 "F.Fab" user "Ref Des/Assembly Top")
		(33 "B.Fab" user "Ref Des/Assembly Bottom")
	)
	(footprint ""
		(layer "F.Cu")
		(at 160.83788 -113.756948)
		(property "Reference" "R3484"
			(at 0 0 0)
			(layer "F.SilkS")
			(hide yes)
			(effects
				(font
					(size 1.27 1.27)
				)
			)
		)
		(property "Value" ""
			(at 0 0 0)
			(layer "F.Fab")
			(effects
				(font
					(size 1.27 1.27)
				)
			)
		)
		(duplicate_pad_numbers_are_jumpers no)
		(fp_line
			(start -0.7874 -0.4064)
			(end 0.7874 -0.4064)
			(stroke
				(width 0.1524)
				(type default)
			)
			(layer "F.SilkS")
		)
		(fp_line
			(start -0.7874 0.4064)
			(end -0.7874 -0.4064)
			(stroke
				(width 0.1524)
				(type default)
			)
			(layer "F.SilkS")
		)
		(fp_line
			(start 0.7874 -0.4064)
			(end 0.7874 0.4064)
			(stroke
				(width 0.1524)
				(type default)
			)
			(layer "F.SilkS")
		)
		(fp_line
			(start 0.7874 0.4064)
			(end -0.7874 0.4064)
			(stroke
				(width 0.1524)
				(type default)
			)
			(layer "F.SilkS")
		)
		(fp_line
			(start -0.67945 -0.305054)
			(end -0.12065 -0.305054)
			(stroke
				(width 0.1)
				(type default)
			)
			(layer "F.Fab")
		)
		(fp_line
			(start -0.67945 0.3048)
			(end -0.67945 -0.305054)
			(stroke
				(width 0.1)
				(type default)
			)
			(layer "F.Fab")
		)
		(fp_line
			(start -0.12065 -0.305054)
			(end -0.12065 -0.2794)
			(stroke
				(width 0.1)
				(type default)
			)
			(layer "F.Fab")
		)
		(fp_line
			(start -0.12065 -0.2794)
			(end 0.12065 -0.2794)
			(stroke
				(width 0.1)
				(type default)
			)
			(layer "F.Fab")
		)
		(fp_line
			(start -0.12065 0.2794)
			(end -0.12065 0.3048)
			(stroke
				(width 0.1)
				(type default)
			)
			(layer "F.Fab")
		)
		(fp_line
			(start -0.12065 0.3048)
			(end -0.67945 0.3048)
			(stroke
				(width 0.1)
				(type default)
			)
			(layer "F.Fab")
		)
		(fp_line
			(start 0.120396 0.2794)
			(end -0.12065 0.2794)
			(stroke
				(width 0.1)
				(type default)
			)
			(layer "F.Fab")
		)
		(fp_line
			(start 0.120396 0.3048)
			(end 0.120396 0.2794)
			(stroke
				(width 0.1)
				(type default)
			)
			(layer "F.Fab")
		)
		(fp_line
			(start 0.12065 -0.3048)
			(end 0.67945 -0.3048)
			(stroke
				(width 0.1)
				(type default)
			)
			(layer "F.Fab")
		)
		(fp_line
			(start 0.12065 -0.2794)
			(end 0.12065 -0.3048)
			(stroke
				(width 0.1)
				(type default)
			)
			(layer "F.Fab")
		)
		(fp_line
			(start 0.67945 -0.3048)
			(end 0.67945 0.3048)
			(stroke
				(width 0.1)
				(type default)
			)
			(layer "F.Fab")
		)
		(fp_line
			(start 0.67945 0.3048)
			(end 0.120396 0.3048)
			(stroke
				(width 0.1)
				(type default)
			)
			(layer "F.Fab")
		)
		(pad "1" smd circle
			(at -0.40005 0)
			(size 0 0)
			(layers "F.Cu" "F.Mask" "F.Paste")
			(net "GPU_FPGA_OVERT_ISO_N")
		)
		(pad "2" smd circle
			(at 0.40005 0)
			(size 0 0)
			(layers "F.Cu" "F.Mask" "F.Paste")
			(net "GPU_FPGA_OVERT_ISO_R_N")
		)
	)
	(footprint ""
		(layer "F.Cu")
		(at 226.733608 -400.759422)
		(property "Reference" "PR3992"
			(at 0 0 0)
			(layer "F.SilkS")
			(hide yes)
			(effects
				(font
					(size 1.27 1.27)
				)
			)
		)
		(property "Value" ""
			(at 0 0 0)
			(layer "F.Fab")
			(effects
				(font
					(size 1.27 1.27)
				)
			)
		)
		(duplicate_pad_numbers_are_jumpers no)
		(fp_line
			(start -0.7874 -0.4064)
			(end 0.7874 -0.4064)
			(stroke
				(width 0.1524)
				(type default)
			)
			(layer "F.SilkS")
		)
		(fp_line
			(start -0.7874 0.4064)
			(end -0.7874 -0.4064)
			(stroke
				(width 0.1524)
				(type default)
			)
			(layer "F.SilkS")
		)
		(fp_line
			(start 0.7874 -0.4064)
			(end 0.7874 0.4064)
			(stroke
				(width 0.1524)
				(type default)
			)
			(layer "F.SilkS")
		)
		(fp_line
			(start 0.7874 0.4064)
			(end -0.7874 0.4064)
			(stroke
				(width 0.1524)
				(type default)
			)
			(layer "F.SilkS")
		)
		(fp_line
			(start -0.67945 -0.305054)
			(end -0.12065 -0.305054)
			(stroke
				(width 0.1)
				(type default)
			)
			(layer "F.Fab")
		)
		(fp_line
			(start -0.67945 0.3048)
			(end -0.67945 -0.305054)
			(stroke
				(width 0.1)
				(type default)
			)
			(layer "F.Fab")
		)
		(fp_line
			(start -0.12065 -0.305054)
			(end -0.12065 -0.2794)
			(stroke
				(width 0.1)
				(type default)
			)
			(layer "F.Fab")
		)
		(fp_line
			(start -0.12065 -0.2794)
			(end 0.12065 -0.2794)
			(stroke
				(width 0.1)
				(type default)
			)
			(layer "F.Fab")
		)
		(fp_line
			(start -0.12065 0.2794)
			(end -0.12065 0.3048)
			(stroke
				(width 0.1)
				(type default)
			)
			(layer "F.Fab")
		)
		(fp_line
			(start -0.12065 0.3048)
			(end -0.67945 0.3048)
			(stroke
				(width 0.1)
				(type default)
			)
			(layer "F.Fab")
		)
		(fp_line
			(start 0.120396 0.2794)
			(end -0.12065 0.2794)
			(stroke
				(width 0.1)
				(type default)
			)
			(layer "F.Fab")
		)
		(fp_line
			(start 0.120396 0.3048)
			(end 0.120396 0.2794)
			(stroke
				(width 0.1)
				(type default)
			)
			(layer "F.Fab")
		)
		(fp_line
			(start 0.12065 -0.3048)
			(end 0.67945 -0.3048)
			(stroke
				(width 0.1)
				(type default)
			)
			(layer "F.Fab")
		)
		(fp_line
			(start 0.12065 -0.2794)
			(end 0.12065 -0.3048)
			(stroke
				(width 0.1)
				(type default)
			)
			(layer "F.Fab")
		)
		(fp_line
			(start 0.67945 -0.3048)
			(end 0.67945 0.3048)
			(stroke
				(width 0.1)
				(type default)
			)
			(layer "F.Fab")
		)
		(fp_line
			(start 0.67945 0.3048)
			(end 0.120396 0.3048)
			(stroke
				(width 0.1)
				(type default)
			)
			(layer "F.Fab")
		)
		(pad "1" smd circle
			(at -0.40005 0)
			(size 0 0)
			(layers "F.Cu" "F.Mask" "F.Paste")
			(net "HSC_D_OC_3")
		)
		(pad "2" smd circle
			(at 0.40005 0)
			(size 0 0)
			(layers "F.Cu" "F.Mask" "F.Paste")
			(net "HSC_D_OC_R")
		)
	)
	(footprint ""
		(layer "F.Cu")
		(at 321.8561 -76.585064 90)
		(property "Reference" "R2975"
			(at 0 0 90)
			(layer "F.SilkS")
			(hide yes)
			(effects
				(font
					(size 1.27 1.27)
				)
			)
		)
		(property "Value" ""
			(at 0 0 90)
			(layer "F.Fab")
			(effects
				(font
					(size 1.27 1.27)
				)
			)
		)
		(duplicate_pad_numbers_are_jumpers no)
		(fp_line
			(start 0.7874 -0.4064)
			(end 0.7874 0.4064)
			(stroke
				(width 0.1524)
				(type default)
			)
			(layer "F.SilkS")
		)
		(fp_line
			(start -0.7874 -0.4064)
			(end 0.7874 -0.4064)
			(stroke
				(width 0.1524)
				(type default)
			)
			(layer "F.SilkS")
		)
		(fp_line
			(start 0.7874 0.4064)
			(end -0.7874 0.4064)
			(stroke
				(width 0.1524)
				(type default)
			)
			(layer "F.SilkS")
		)
		(fp_line
			(start -0.7874 0.4064)
			(end -0.7874 -0.4064)
			(stroke
				(width 0.1524)
				(type default)
			)
			(layer "F.SilkS")
		)
		(fp_line
			(start -0.12065 -0.305054)
			(end -0.12065 -0.2794)
			(stroke
				(width 0.1)
				(type default)
			)
			(layer "F.Fab")
		)
		(fp_line
			(start -0.67945 -0.305054)
			(end -0.12065 -0.305054)
			(stroke
				(width 0.1)
				(type default)
			)
			(layer "F.Fab")
		)
		(fp_line
			(start 0.67945 -0.3048)
			(end 0.67945 0.3048)
			(stroke
				(width 0.1)
				(type default)
			)
			(layer "F.Fab")
		)
		(fp_line
			(start 0.12065 -0.3048)
			(end 0.67945 -0.3048)
			(stroke
				(width 0.1)
				(type default)
			)
			(layer "F.Fab")
		)
		(fp_line
			(start 0.12065 -0.2794)
			(end 0.12065 -0.3048)
			(stroke
				(width 0.1)
				(type default)
			)
			(layer "F.Fab")
		)
		(fp_line
			(start -0.12065 -0.2794)
			(end 0.12065 -0.2794)
			(stroke
				(width 0.1)
				(type default)
			)
			(layer "F.Fab")
		)
		(fp_line
			(start 0.120396 0.2794)
			(end -0.12065 0.2794)
			(stroke
				(width 0.1)
				(type default)
			)
			(layer "F.Fab")
		)
		(fp_line
			(start -0.12065 0.2794)
			(end -0.12065 0.3048)
			(stroke
				(width 0.1)
				(type default)
			)
			(layer "F.Fab")
		)
		(fp_line
			(start 0.67945 0.3048)
			(end 0.120396 0.3048)
			(stroke
				(width 0.1)
				(type default)
			)
			(layer "F.Fab")
		)
		(fp_line
			(start 0.120396 0.3048)
			(end 0.120396 0.2794)
			(stroke
				(width 0.1)
				(type default)
			)
			(layer "F.Fab")
		)
		(fp_line
			(start -0.12065 0.3048)
			(end -0.67945 0.3048)
			(stroke
				(width 0.1)
				(type default)
			)
			(layer "F.Fab")
		)
		(fp_line
			(start -0.67945 0.3048)
			(end -0.67945 -0.305054)
			(stroke
				(width 0.1)
				(type default)
			)
			(layer "F.Fab")
		)
		(pad "1" smd circle
			(at -0.40005 0 90)
			(size 0 0)
			(layers "F.Cu" "F.Mask" "F.Paste")
			(net "FAB_REV_ID1")
		)
		(pad "2" smd circle
			(at 0.40005 0 90)
			(size 0 0)
			(layers "F.Cu" "F.Mask" "F.Paste")
			(net "GND")
		)
	)
	(footprint ""
		(layer "F.Cu")
		(at 13.800582 -410.802836 90)
		(property "Reference" "R2693"
			(at 0 0 90)
			(layer "F.SilkS")
			(hide yes)
			(effects
				(font
					(size 1.27 1.27)
				)
			)
		)
		(property "Value" ""
			(at 0 0 90)
			(layer "F.Fab")
			(effects
				(font
					(size 1.27 1.27)
				)
			)
		)
		(duplicate_pad_numbers_are_jumpers no)
		(fp_line
			(start 0.7874 -0.4064)
			(end 0.7874 0.4064)
			(stroke
				(width 0.1524)
				(type default)
			)
			(layer "F.SilkS")
		)
		(fp_line
			(start -0.7874 -0.4064)
			(end 0.7874 -0.4064)
			(stroke
				(width 0.1524)
				(type default)
			)
			(layer "F.SilkS")
		)
		(fp_line
			(start 0.7874 0.4064)
			(end -0.7874 0.4064)
			(stroke
				(width 0.1524)
				(type default)
			)
			(layer "F.SilkS")
		)
		(fp_line
			(start -0.7874 0.4064)
			(end -0.7874 -0.4064)
			(stroke
				(width 0.1524)
				(type default)
			)
			(layer "F.SilkS")
		)
		(fp_line
			(start -0.12065 -0.305054)
			(end -0.12065 -0.2794)
			(stroke
				(width 0.1)
				(type default)
			)
			(layer "F.Fab")
		)
		(fp_line
			(start -0.67945 -0.305054)
			(end -0.12065 -0.305054)
			(stroke
				(width 0.1)
				(type default)
			)
			(layer "F.Fab")
		)
		(fp_line
			(start 0.67945 -0.3048)
			(end 0.67945 0.3048)
			(stroke
				(width 0.1)
				(type default)
			)
			(layer "F.Fab")
		)
		(fp_line
			(start 0.12065 -0.3048)
			(end 0.67945 -0.3048)
			(stroke
				(width 0.1)
				(type default)
			)
			(layer "F.Fab")
		)
		(fp_line
			(start 0.12065 -0.2794)
			(end 0.12065 -0.3048)
			(stroke
				(width 0.1)
				(type default)
			)
			(layer "F.Fab")
		)
		(fp_line
			(start -0.12065 -0.2794)
			(end 0.12065 -0.2794)
			(stroke
				(width 0.1)
				(type default)
			)
			(layer "F.Fab")
		)
		(fp_line
			(start 0.120396 0.2794)
			(end -0.12065 0.2794)
			(stroke
				(width 0.1)
				(type default)
			)
			(layer "F.Fab")
		)
		(fp_line
			(start -0.12065 0.2794)
			(end -0.12065 0.3048)
			(stroke
				(width 0.1)
				(type default)
			)
			(layer "F.Fab")
		)
		(fp_line
			(start 0.67945 0.3048)
			(end 0.120396 0.3048)
			(stroke
				(width 0.1)
				(type default)
			)
			(layer "F.Fab")
		)
		(fp_line
			(start 0.120396 0.3048)
			(end 0.120396 0.2794)
			(stroke
				(width 0.1)
				(type default)
			)
			(layer "F.Fab")
		)
		(fp_line
			(start -0.12065 0.3048)
			(end -0.67945 0.3048)
			(stroke
				(width 0.1)
				(type default)
			)
			(layer "F.Fab")
		)
		(fp_line
			(start -0.67945 0.3048)
			(end -0.67945 -0.305054)
			(stroke
				(width 0.1)
				(type default)
			)
			(layer "F.Fab")
		)
		(pad "1" smd circle
			(at -0.40005 0 90)
			(size 0 0)
			(layers "F.Cu" "F.Mask" "F.Paste")
			(net "P3V3_AUX")
		)
		(pad "2" smd circle
			(at 0.40005 0 90)
			(size 0 0)
			(layers "F.Cu" "F.Mask" "F.Paste")
			(net "TCA9539_0_ADD1")
		)
	)
	(footprint ""
		(layer "F.Cu")
		(at 164.52088 -42.255948)
		(property "Reference" "R486"
			(at 0 0 0)
			(layer "F.SilkS")
			(hide yes)
			(effects
				(font
					(size 1.27 1.27)
				)
			)
		)
		(property "Value" ""
			(at 0 0 0)
			(layer "F.Fab")
			(effects
				(font
					(size 1.27 1.27)
				)
			)
		)
		(duplicate_pad_numbers_are_jumpers no)
		(fp_line
			(start -0.7874 -0.4064)
			(end 0.7874 -0.4064)
			(stroke
				(width 0.1524)
				(type default)
			)
			(layer "F.SilkS")
		)
		(fp_line
			(start -0.7874 0.4064)
			(end -0.7874 -0.4064)
			(stroke
				(width 0.1524)
				(type default)
			)
			(layer "F.SilkS")
		)
		(fp_line
			(start 0.7874 -0.4064)
			(end 0.7874 0.4064)
			(stroke
				(width 0.1524)
				(type default)
			)
			(layer "F.SilkS")
		)
		(fp_line
			(start 0.7874 0.4064)
			(end -0.7874 0.4064)
			(stroke
				(width 0.1524)
				(type default)
			)
			(layer "F.SilkS")
		)
		(fp_line
			(start -0.67945 -0.305054)
			(end -0.12065 -0.305054)
			(stroke
				(width 0.1)
				(type default)
			)
			(layer "F.Fab")
		)
		(fp_line
			(start -0.67945 0.3048)
			(end -0.67945 -0.305054)
			(stroke
				(width 0.1)
				(type default)
			)
			(layer "F.Fab")
		)
		(fp_line
			(start -0.12065 -0.305054)
			(end -0.12065 -0.2794)
			(stroke
				(width 0.1)
				(type default)
			)
			(layer "F.Fab")
		)
		(fp_line
			(start -0.12065 -0.2794)
			(end 0.12065 -0.2794)
			(stroke
				(width 0.1)
				(type default)
			)
			(layer "F.Fab")
		)
		(fp_line
			(start -0.12065 0.2794)
			(end -0.12065 0.3048)
			(stroke
				(width 0.1)
				(type default)
			)
			(layer "F.Fab")
		)
		(fp_line
			(start -0.12065 0.3048)
			(end -0.67945 0.3048)
			(stroke
				(width 0.1)
				(type default)
			)
			(layer "F.Fab")
		)
		(fp_line
			(start 0.120396 0.2794)
			(end -0.12065 0.2794)
			(stroke
				(width 0.1)
				(type default)
			)
			(layer "F.Fab")
		)
		(fp_line
			(start 0.120396 0.3048)
			(end 0.120396 0.2794)
			(stroke
				(width 0.1)
				(type default)
			)
			(layer "F.Fab")
		)
		(fp_line
			(start 0.12065 -0.3048)
			(end 0.67945 -0.3048)
			(stroke
				(width 0.1)
				(type default)
			)
			(layer "F.Fab")
		)
		(fp_line
			(start 0.12065 -0.2794)
			(end 0.12065 -0.3048)
			(stroke
				(width 0.1)
				(type default)
			)
			(layer "F.Fab")
		)
		(fp_line
			(start 0.67945 -0.3048)
			(end 0.67945 0.3048)
			(stroke
				(width 0.1)
				(type default)
			)
			(layer "F.Fab")
		)
		(fp_line
			(start 0.67945 0.3048)
			(end 0.120396 0.3048)
			(stroke
				(width 0.1)
				(type default)
			)
			(layer "F.Fab")
		)
		(pad "1" smd circle
			(at -0.40005 0)
			(size 0 0)
			(layers "F.Cu" "F.Mask" "F.Paste")
			(net "M2_SSD0_CLKREQ_EN_N")
		)
		(pad "2" smd circle
			(at 0.40005 0)
			(size 0 0)
			(layers "F.Cu" "F.Mask" "F.Paste")
			(net "M2_SSD0_CLKREQ_EN_N_BUF")
		)
	)
	(footprint ""
		(layer "F.Cu")
		(at 107.3658 -408.686)
		(property "Reference" "Q151"
			(at 2.76098 0.738632 0)
			(unlocked yes)
			(layer "F.SilkS")
			(effects
				(font
					(size 0.7874 0.5842)
					(thickness 0.1524)
				)
				(justify left)
			)
		)
		(property "Value" ""
			(at 0 0 0)
			(layer "F.Fab")
			(effects
				(font
					(size 1.27 1.27)
				)
			)
		)
		(duplicate_pad_numbers_are_jumpers no)
		(fp_line
			(start -1.332738 -1.100074)
			(end -0.4826 -1.100074)
			(stroke
				(width 0.1524)
				(type default)
			)
			(layer "F.SilkS")
		)
		(fp_line
			(start -1.332738 1.100074)
			(end -1.332738 -1.100074)
			(stroke
				(width 0.1524)
				(type default)
			)
			(layer "F.SilkS")
		)
		(fp_line
			(start -0.4826 -1.100074)
			(end 0 -0.541274)
			(stroke
				(width 0.1524)
				(type default)
			)
			(layer "F.SilkS")
		)
		(fp_line
			(start 0 -0.541274)
			(end 0.4826 -1.100074)
			(stroke
				(width 0.1524)
				(type default)
			)
			(layer "F.SilkS")
		)
		(fp_line
			(start 0.4826 -1.100074)
			(end 1.332738 -1.100074)
			(stroke
				(width 0.1524)
				(type default)
			)
			(layer "F.SilkS")
		)
		(fp_line
			(start 1.332738 -1.100074)
			(end 1.332738 1.100074)
			(stroke
				(width 0.1524)
				(type default)
			)
			(layer "F.SilkS")
		)
		(fp_line
			(start 1.332738 1.100074)
			(end -1.332738 1.100074)
			(stroke
				(width 0.1524)
				(type default)
			)
			(layer "F.SilkS")
		)
		(fp_poly
			(pts
				(xy -2.2352 -0.298958) (xy -2.2352 -1.001014) (xy -1.533144 -0.649986)
			)
			(stroke
				(width 0)
				(type default)
			)
			(fill yes)
			(layer "F.SilkS")
		)
		(fp_line
			(start -0.674878 -1.100074)
			(end 0.674878 -1.100074)
			(stroke
				(width 0.1)
				(type default)
			)
			(layer "F.Fab")
		)
		(fp_line
			(start -0.674878 1.100074)
			(end -0.674878 -1.100074)
			(stroke
				(width 0.1)
				(type default)
			)
			(layer "F.Fab")
		)
		(fp_line
			(start 0.674878 -1.100074)
			(end 0.674878 1.100074)
			(stroke
				(width 0.1)
				(type default)
			)
			(layer "F.Fab")
		)
		(fp_line
			(start 0.674878 1.100074)
			(end -0.674878 1.100074)
			(stroke
				(width 0.1)
				(type default)
			)
			(layer "F.Fab")
		)
		(fp_poly
			(pts
				(xy -2.2352 -0.298958) (xy -2.2352 -1.001014) (xy -1.533144 -0.649986)
			)
			(stroke
				(width 0)
				(type default)
			)
			(fill yes)
			(layer "F.Fab")
		)
		(pad "1" smd rect
			(at -0.94996 -0.649986 90)
			(size 0.4318 0.508)
			(layers "F.Cu" "F.Mask" "F.Paste")
			(net "GND")
		)
		(pad "2" smd rect
			(at -0.94996 0 90)
			(size 0.4318 0.508)
			(layers "F.Cu" "F.Mask" "F.Paste")
			(net "PRSNT_SWB_N")
		)
		(pad "3" smd rect
			(at -0.94996 0.649986 90)
			(size 0.4318 0.508)
			(layers "F.Cu" "F.Mask" "F.Paste")
			(net "PRSNT_SWB_ISO_N")
		)
		(pad "4" smd rect
			(at 0.94996 0.649986 90)
			(size 0.4318 0.508)
			(layers "F.Cu" "F.Mask" "F.Paste")
			(net "GND")
		)
		(pad "5" smd rect
			(at 0.94996 0 90)
			(size 0.4318 0.508)
			(layers "F.Cu" "F.Mask" "F.Paste")
			(net "PRSNT_SWB")
		)
		(pad "6" smd rect
			(at 0.94996 -0.649986 90)
			(size 0.4318 0.508)
			(layers "F.Cu" "F.Mask" "F.Paste")
			(net "PRSNT_SWB")
		)
	)
)
